(kicad_pcb
	(version 20241229)
	(generator "pcbnew")
	(generator_version "9.0")
	(general
		(thickness 1.294)
		(legacy_teardrops no)
	)
	(paper "A3")
	(title_block
		(title "Kintex 410T devboard")
		(date "2024-04-03")
		(rev "1.1.2")
		(comment 9 "footprints 282-287 of 975")
	)
	(layers
		(0 "F.Cu" mixed)
		(4 "In1.Cu" power)
		(6 "In2.Cu" power)
		(8 "In3.Cu" mixed)
		(10 "In4.Cu" power)
		(12 "In5.Cu" mixed)
		(14 "In6.Cu" power)
		(16 "In7.Cu" mixed)
		(18 "In8.Cu" power)
		(2 "B.Cu" mixed)
		(9 "F.Adhes" user "F.Adhesive")
		(11 "B.Adhes" user "B.Adhesive")
		(13 "F.Paste" user)
		(15 "B.Paste" user)
		(5 "F.SilkS" user "F.Silkscreen")
		(7 "B.SilkS" user "B.Silkscreen")
		(1 "F.Mask" user)
		(3 "B.Mask" user)
		(17 "Dwgs.User" user "User.Drawings")
		(19 "Cmts.User" user "User.Comments")
		(21 "Eco1.User" user "User.Eco1")
		(23 "Eco2.User" user "User.Eco2")
		(25 "Edge.Cuts" user)
		(27 "Margin" user)
		(31 "F.CrtYd" user "F.Courtyard")
		(29 "B.CrtYd" user "B.Courtyard")
		(35 "F.Fab" user)
		(33 "B.Fab" user)
	)
	(footprint "antmicro-footprints:R_0402_1005Metric"
		(layer "F.Cu")
		(at 225.1 114.2)
		(descr "Resistor SMD 0402")
		(tags "resistor SMD 0402")
		(property "Reference" "R94"
			(at -3.65 0.4 0)
			(layer "F.SilkS")
			(effects
				(font
					(size 0.7 0.7)
					(thickness 0.15)
				)
				(justify left bottom)
			)
		)
		(property "Value" "R_10k_0402"
			(at 0 1.4 0)
			(layer "F.Fab")
			(effects
				(font
					(size 0.7 0.7)
					(thickness 0.15)
				)
				(justify left bottom)
			)
		)
		(property "Description" "SMD Chip Resistor, 10 kohm, ± 1%, 62.5 mW, 0402 [1005 Metric], Thick Film, General Purpose"
			(at 0 0 0)
			(layer "F.Fab")
			(hide yes)
			(effects
				(font
					(size 1.27 1.27)
					(thickness 0.15)
				)
			)
		)
		(property "Author" "Antmicro"
			(at 0 0 0)
			(layer "F.Fab")
			(hide yes)
			(effects
				(font
					(size 1 1)
					(thickness 0.15)
				)
			)
		)
		(property "License" "Apache-2.0"
			(at 0 0 0)
			(layer "F.Fab")
			(hide yes)
			(effects
				(font
					(size 1 1)
					(thickness 0.15)
				)
			)
		)
		(property "MPN" "CR0402-FX-1002GLF"
			(at 0 0 0)
			(layer "F.Fab")
			(hide yes)
			(effects
				(font
					(size 1 1)
					(thickness 0.15)
				)
			)
		)
		(property "Manufacturer" "Bourns"
			(at 0 0 0)
			(layer "F.Fab")
			(hide yes)
			(effects
				(font
					(size 1 1)
					(thickness 0.15)
				)
			)
		)
		(property "Tolerance" "1%"
			(at 0 0 0)
			(layer "F.Fab")
			(hide yes)
			(effects
				(font
					(size 1 1)
					(thickness 0.15)
				)
			)
		)
		(property "Val" "10k"
			(at 0 0 0)
			(layer "F.Fab")
			(hide yes)
			(effects
				(font
					(size 1 1)
					(thickness 0.15)
				)
			)
		)
		(sheetname "SPI Flash + SD Card")
		(sheetfile "spi-flash.kicad_sch")
		(attr smd)
		(fp_rect
			(start -0.925 -0.47)
			(end 0.925 0.47)
			(stroke
				(width 0.05)
				(type default)
			)
			(fill no)
			(layer "F.CrtYd")
		)
		(fp_rect
			(start -0.5 -0.25)
			(end 0.5 0.25)
			(stroke
				(width 0.15)
				(type solid)
			)
			(fill no)
			(layer "F.Fab")
		)
		(pad "1" smd roundrect
			(at -0.48 0)
			(size 0.59 0.64)
			(layers "F.Cu" "F.Mask" "F.Paste")
			(roundrect_rratio 0.25)
			(net 419 "/FPGA Bank 16 & 17/USR_FLASH_1.DQ2")
			(pintype "passive")
		)
		(pad "2" smd roundrect
			(at 0.48 0)
			(size 0.59 0.64)
			(layers "F.Cu" "F.Mask" "F.Paste")
			(roundrect_rratio 0.25)
			(net 3 "VCC_USR_B")
			(pintype "passive")
		)
	)
	(footprint "antmicro-footprints:R_0402_1005Metric"
		(layer "F.Cu")
		(at 250.399 97.5 90)
		(descr "Resistor SMD 0402")
		(tags "resistor SMD 0402")
		(property "Reference" "R344"
			(at 0.15 -0.449 90)
			(layer "F.SilkS")
			(effects
				(font
					(size 0.7 0.7)
					(thickness 0.15)
				)
				(justify left bottom)
			)
		)
		(property "Value" "R_0R_0402"
			(at 0 1.4 90)
			(layer "F.Fab")
			(effects
				(font
					(size 0.7 0.7)
					(thickness 0.15)
				)
				(justify left bottom)
			)
		)
		(property "Description" "SMD Chip Resistor, Jumper, 0 ohm, 100 mW, 0402 [1005 Metric], Thick Film, General Purpose"
			(at 0 0 90)
			(layer "F.Fab")
			(hide yes)
			(effects
				(font
					(size 1.27 1.27)
					(thickness 0.15)
				)
			)
		)
		(property "Author" "Antmicro"
			(at 347.899 -152.899 0)
			(layer "F.Fab")
			(hide yes)
			(effects
				(font
					(size 1 1)
					(thickness 0.15)
				)
			)
		)
		(property "Current" "1A"
			(at 347.899 -152.899 0)
			(layer "F.Fab")
			(hide yes)
			(effects
				(font
					(size 1 1)
					(thickness 0.15)
				)
			)
		)
		(property "License" "Apache-2.0"
			(at 347.899 -152.899 0)
			(layer "F.Fab")
			(hide yes)
			(effects
				(font
					(size 1 1)
					(thickness 0.15)
				)
			)
		)
		(property "MPN" "ERJ2GE0R00X"
			(at 347.899 -152.899 0)
			(layer "F.Fab")
			(hide yes)
			(effects
				(font
					(size 1 1)
					(thickness 0.15)
				)
			)
		)
		(property "Manufacturer" "Panasonic"
			(at 347.899 -152.899 0)
			(layer "F.Fab")
			(hide yes)
			(effects
				(font
					(size 1 1)
					(thickness 0.15)
				)
			)
		)
		(property "Tolerance" ""
			(at 347.899 -152.899 0)
			(layer "F.Fab")
			(hide yes)
			(effects
				(font
					(size 1 1)
					(thickness 0.15)
				)
			)
		)
		(property "Val" "0R"
			(at 347.899 -152.899 0)
			(layer "F.Fab")
			(hide yes)
			(effects
				(font
					(size 1 1)
					(thickness 0.15)
				)
			)
		)
		(sheetname "USB PHY")
		(sheetfile "usb-phy.kicad_sch")
		(attr smd)
		(fp_rect
			(start -0.925 -0.47)
			(end 0.925 0.47)
			(stroke
				(width 0.05)
				(type default)
			)
			(fill no)
			(layer "F.CrtYd")
		)
		(fp_rect
			(start -0.5 -0.25)
			(end 0.5 0.25)
			(stroke
				(width 0.15)
				(type solid)
			)
			(fill no)
			(layer "F.Fab")
		)
		(pad "1" smd roundrect
			(at -0.48 0 90)
			(size 0.59 0.64)
			(layers "F.Cu" "F.Mask" "F.Paste")
			(roundrect_rratio 0.25)
			(net 569 "/FPGA Bank 12 & 13/USB_HOST.VBUS_PEN")
			(pintype "passive")
		)
		(pad "2" smd roundrect
			(at 0.48 0 90)
			(size 0.59 0.64)
			(layers "F.Cu" "F.Mask" "F.Paste")
			(roundrect_rratio 0.25)
			(net 583 "/USB PHY/USB_HOST_VBUS_EN")
			(pintype "passive")
		)
	)
	(footprint "antmicro-footprints:C_0402_1005Metric"
		(layer "F.Cu")
		(at 228.725 137.8 -90)
		(descr "Capacitor SMD 0402")
		(tags "capacitor SMD 0402")
		(property "Reference" "C369"
			(at -1.55 -2.375 180)
			(layer "F.SilkS")
			(effects
				(font
					(size 0.7 0.7)
					(thickness 0.15)
				)
				(justify right bottom)
			)
		)
		(property "Value" "C_100n_0402"
			(at 0 1.4 90)
			(layer "F.Fab")
			(effects
				(font
					(size 0.7 0.7)
					(thickness 0.15)
				)
				(justify right bottom)
			)
		)
		(property "Description" "SMD Multilayer Ceramic Capacitor, 0.1 µF, 50 V, 0402 [1005 Metric], ± 10%, X5R, GRM Series"
			(at 0 0 270)
			(layer "F.Fab")
			(hide yes)
			(effects
				(font
					(size 1.27 1.27)
					(thickness 0.15)
				)
			)
		)
		(property "Author" "Antmicro"
			(at 90.925 366.525 0)
			(layer "F.Fab")
			(hide yes)
			(effects
				(font
					(size 1 1)
					(thickness 0.15)
				)
			)
		)
		(property "Dielectric" "X5R"
			(at 90.925 366.525 0)
			(layer "F.Fab")
			(hide yes)
			(effects
				(font
					(size 1 1)
					(thickness 0.15)
				)
			)
		)
		(property "License" "Apache-2.0"
			(at 90.925 366.525 0)
			(layer "F.Fab")
			(hide yes)
			(effects
				(font
					(size 1 1)
					(thickness 0.15)
				)
			)
		)
		(property "MPN" "GRM155R61H104KE14D"
			(at 90.925 366.525 0)
			(layer "F.Fab")
			(hide yes)
			(effects
				(font
					(size 1 1)
					(thickness 0.15)
				)
			)
		)
		(property "Manufacturer" "Murata"
			(at 90.925 366.525 0)
			(layer "F.Fab")
			(hide yes)
			(effects
				(font
					(size 1 1)
					(thickness 0.15)
				)
			)
		)
		(property "Val" "100n"
			(at 90.925 366.525 0)
			(layer "F.Fab")
			(hide yes)
			(effects
				(font
					(size 1 1)
					(thickness 0.15)
				)
			)
		)
		(property "Voltage" "50V"
			(at 90.925 366.525 0)
			(layer "F.Fab")
			(hide yes)
			(effects
				(font
					(size 1 1)
					(thickness 0.15)
				)
			)
		)
		(sheetname "Clocks")
		(sheetfile "clocks.kicad_sch")
		(attr smd)
		(fp_rect
			(start -0.925 -0.47)
			(end 0.925 0.47)
			(stroke
				(width 0.05)
				(type default)
			)
			(fill no)
			(layer "F.CrtYd")
		)
		(fp_line
			(start -0.494 0.248)
			(end -0.494 -0.25)
			(stroke
				(width 0.15)
				(type solid)
			)
			(layer "F.Fab")
		)
		(fp_line
			(start 0.504 0.248)
			(end -0.494 0.248)
			(stroke
				(width 0.15)
				(type solid)
			)
			(layer "F.Fab")
		)
		(fp_line
			(start -0.494 -0.25)
			(end 0.504 -0.25)
			(stroke
				(width 0.15)
				(type solid)
			)
			(layer "F.Fab")
		)
		(fp_line
			(start 0.504 -0.25)
			(end 0.504 0.248)
			(stroke
				(width 0.15)
				(type solid)
			)
			(layer "F.Fab")
		)
		(pad "1" smd roundrect
			(at -0.48 0 270)
			(size 0.59 0.64)
			(layers "F.Cu" "F.Mask" "F.Paste")
			(roundrect_rratio 0.25)
			(net 1 "GND")
			(pintype "passive")
		)
		(pad "2" smd roundrect
			(at 0.48 0 270)
			(size 0.59 0.64)
			(layers "F.Cu" "F.Mask" "F.Paste")
			(roundrect_rratio 0.25)
			(net 1231 "Net-(C366-Pad2)")
			(pintype "passive")
		)
	)
	(footprint "antmicro-footprints:C_0402_1005Metric"
		(layer "F.Cu")
		(at 173.570001 124.922501 180)
		(descr "Capacitor SMD 0402")
		(tags "capacitor SMD 0402")
		(property "Reference" "C307"
			(at -3.729999 -0.329999 0)
			(layer "F.SilkS")
			(effects
				(font
					(size 0.7 0.7)
					(thickness 0.15)
				)
				(justify right bottom)
			)
		)
		(property "Value" "C_100n_0402"
			(at 0 1.4 0)
			(layer "F.Fab")
			(effects
				(font
					(size 0.7 0.7)
					(thickness 0.15)
				)
				(justify right bottom)
			)
		)
		(property "Description" "SMD Multilayer Ceramic Capacitor, 0.1 µF, 50 V, 0402 [1005 Metric], ± 10%, X5R, GRM Series"
			(at 0 0 180)
			(layer "F.Fab")
			(hide yes)
			(effects
				(font
					(size 1.27 1.27)
					(thickness 0.15)
				)
			)
		)
		(property "Author" "Antmicro"
			(at 347.140002 249.845002 0)
			(layer "F.Fab")
			(hide yes)
			(effects
				(font
					(size 1 1)
					(thickness 0.15)
				)
			)
		)
		(property "Dielectric" "X5R"
			(at 347.140002 249.845002 0)
			(layer "F.Fab")
			(hide yes)
			(effects
				(font
					(size 1 1)
					(thickness 0.15)
				)
			)
		)
		(property "License" "Apache-2.0"
			(at 347.140002 249.845002 0)
			(layer "F.Fab")
			(hide yes)
			(effects
				(font
					(size 1 1)
					(thickness 0.15)
				)
			)
		)
		(property "MPN" "GRM155R61H104KE14D"
			(at 347.140002 249.845002 0)
			(layer "F.Fab")
			(hide yes)
			(effects
				(font
					(size 1 1)
					(thickness 0.15)
				)
			)
		)
		(property "Manufacturer" "Murata"
			(at 347.140002 249.845002 0)
			(layer "F.Fab")
			(hide yes)
			(effects
				(font
					(size 1 1)
					(thickness 0.15)
				)
			)
		)
		(property "Val" "100n"
			(at 347.140002 249.845002 0)
			(layer "F.Fab")
			(hide yes)
			(effects
				(font
					(size 1 1)
					(thickness 0.15)
				)
			)
		)
		(property "Voltage" "50V"
			(at 347.140002 249.845002 0)
			(layer "F.Fab")
			(hide yes)
			(effects
				(font
					(size 1 1)
					(thickness 0.15)
				)
			)
		)
		(sheetname "FMC+ HSPC")
		(sheetfile "fmc-hspc.kicad_sch")
		(attr smd)
		(fp_rect
			(start -0.925 -0.47)
			(end 0.925 0.47)
			(stroke
				(width 0.05)
				(type default)
			)
			(fill no)
			(layer "F.CrtYd")
		)
		(fp_line
			(start 0.504 0.248)
			(end -0.494 0.248)
			(stroke
				(width 0.15)
				(type solid)
			)
			(layer "F.Fab")
		)
		(fp_line
			(start 0.504 -0.25)
			(end 0.504 0.248)
			(stroke
				(width 0.15)
				(type solid)
			)
			(layer "F.Fab")
		)
		(fp_line
			(start -0.494 0.248)
			(end -0.494 -0.25)
			(stroke
				(width 0.15)
				(type solid)
			)
			(layer "F.Fab")
		)
		(fp_line
			(start -0.494 -0.25)
			(end 0.504 -0.25)
			(stroke
				(width 0.15)
				(type solid)
			)
			(layer "F.Fab")
		)
		(pad "1" smd roundrect
			(at -0.48 0 180)
			(size 0.59 0.64)
			(layers "F.Cu" "F.Mask" "F.Paste")
			(roundrect_rratio 0.25)
			(net 89 "/FMC+ HSPC/GTX115.TX3_N")
			(pintype "passive")
		)
		(pad "2" smd roundrect
			(at 0.48 0 180)
			(size 0.59 0.64)
			(layers "F.Cu" "F.Mask" "F.Paste")
			(roundrect_rratio 0.25)
			(net 88 "/FMC+ HSPC/GTX_TX4_C_N")
			(pintype "passive")
		)
	)
	(footprint "antmicro-footprints:NetTie-2_SMD_Pad0.127mm"
		(layer "F.Cu")
		(at 247.7 143.602 90)
		(descr "Net tie, 2 pin, 0.127mm  SMD pads")
		(tags "net tie")
		(property "Reference" "NT3"
			(at -0.128 -1.345 90)
			(layer "F.SilkS")
			(hide yes)
			(effects
				(font
					(size 0.7 0.7)
					(thickness 0.15)
				)
				(justify left bottom)
			)
		)
		(property "Value" "Net-Tie_2"
			(at 0 1.199 90)
			(layer "F.Fab")
			(effects
				(font
					(size 0.7 0.7)
					(thickness 0.15)
				)
				(justify left bottom)
			)
		)
		(property "Description" "Net tie, 2 pins"
			(at 0 0 90)
			(layer "F.Fab")
			(hide yes)
			(effects
				(font
					(size 1.27 1.27)
					(thickness 0.15)
				)
			)
		)
		(property "Author" "Antmicro"
			(at 391.302 -104.098 0)
			(layer "F.Fab")
			(hide yes)
			(effects
				(font
					(size 1 1)
					(thickness 0.15)
				)
			)
		)
		(property "License" "Apache-2.0"
			(at 391.302 -104.098 0)
			(layer "F.Fab")
			(hide yes)
			(effects
				(font
					(size 1 1)
					(thickness 0.15)
				)
			)
		)
		(property "MPN" ""
			(at 391.302 -104.098 0)
			(layer "F.Fab")
			(hide yes)
			(effects
				(font
					(size 1 1)
					(thickness 0.15)
				)
			)
		)
		(property "Manufacturer" ""
			(at 391.302 -104.098 0)
			(layer "F.Fab")
			(hide yes)
			(effects
				(font
					(size 1 1)
					(thickness 0.15)
				)
			)
		)
		(sheetname "FPGA Config")
		(sheetfile "fpga-config.kicad_sch")
		(attr exclude_from_pos_files)
		(net_tie_pad_groups "1, 2")
		(fp_poly
			(pts
				(xy -0.0635 -0.0635) (xy 0.0625 -0.0635) (xy 0.0625 0.0635) (xy -0.0635 0.0635)
			)
			(stroke
				(width 0)
				(type solid)
			)
			(fill yes)
			(layer "F.Cu")
		)
		(pad "1" smd roundrect
			(at -0.127 0 270)
			(size 0.127 0.127)
			(layers "F.Cu")
			(roundrect_rratio 0.5)
			(chamfer_ratio 0)
			(chamfer top_left bottom_left)
			(net 1312 "/SUP_MCU.FPGA_M0")
			(pinfunction "1")
			(pintype "passive")
		)
		(pad "2" smd roundrect
			(at 0.126 0 90)
			(size 0.127 0.127)
			(layers "F.Cu")
			(roundrect_rratio 0.5)
			(chamfer_ratio 0)
			(chamfer top_left bottom_left)
			(net 300 "/FPGA Config/MODE0")
			(pinfunction "2")
			(pintype "passive")
		)
	)
	(footprint "antmicro-footprints:Onsemi_WLCSP6_1.40x0.90"
		(layer "F.Cu")
		(at 169.45 176)
		(property "Reference" "U34"
			(at -1.1 1.85 0)
			(layer "F.SilkS")
			(effects
				(font
					(size 0.7 0.7)
					(thickness 0.15)
				)
				(justify left bottom)
			)
		)
		(property "Value" "NCP451AFCT2G"
			(at -6.21 1.96 0)
			(layer "F.Fab")
			(effects
				(font
					(size 0.7 0.7)
					(thickness 0.15)
				)
				(justify left bottom)
			)
		)
		(property "Description" "Power Load Switch, High Side, Active High, 1 Output, 0.012 ohm On State, 5.5 V supp, 3 A, WLCSP-6"
			(at 0 0 0)
			(layer "F.Fab")
			(hide yes)
			(effects
				(font
					(size 1.27 1.27)
					(thickness 0.15)
				)
			)
		)
		(property "Author" "Antmicro"
			(at 0 0 0)
			(layer "F.Fab")
			(hide yes)
			(effects
				(font
					(size 1 1)
					(thickness 0.15)
				)
			)
		)
		(property "DNP" "DNP"
			(at 0 0 0)
			(layer "F.Fab")
			(hide yes)
			(effects
				(font
					(size 1 1)
					(thickness 0.15)
				)
			)
		)
		(property "License" "Apache-2.0"
			(at 0 0 0)
			(layer "F.Fab")
			(hide yes)
			(effects
				(font
					(size 1 1)
					(thickness 0.15)
				)
			)
		)
		(property "MPN" "NCP451AFCT2G"
			(at 0 0 0)
			(layer "F.Fab")
			(hide yes)
			(effects
				(font
					(size 1 1)
					(thickness 0.15)
				)
			)
		)
		(property "Manufacturer" "ON Semiconductor"
			(at 0 0 0)
			(layer "F.Fab")
			(hide yes)
			(effects
				(font
					(size 1 1)
					(thickness 0.15)
				)
			)
		)
		(property "dnp" ""
			(at 0 0 0)
			(layer "F.Fab")
			(hide yes)
			(effects
				(font
					(size 1 1)
					(thickness 0.15)
				)
			)
		)
		(property "exclude_from_bom" ""
			(at 0 0 0)
			(layer "F.Fab")
			(hide yes)
			(effects
				(font
					(size 1 1)
					(thickness 0.15)
				)
			)
		)
		(sheetname "DC-DC Converters")
		(sheetfile "dc-dc.kicad_sch")
		(attr smd exclude_from_bom)
		(fp_line
			(start -0.5 -0.47)
			(end -0.5 -0.77)
			(stroke
				(width 0.15)
				(type solid)
			)
			(layer "F.SilkS")
		)
		(fp_line
			(start -0.5 0.47)
			(end -0.5 0.77)
			(stroke
				(width 0.15)
				(type solid)
			)
			(layer "F.SilkS")
		)
		(fp_line
			(start -0.2 -0.77)
			(end -0.5 -0.77)
			(stroke
				(width 0.15)
				(type solid)
			)
			(layer "F.SilkS")
		)
		(fp_line
			(start -0.2 0.77)
			(end -0.5 0.77)
			(stroke
				(width 0.15)
				(type solid)
			)
			(layer "F.SilkS")
		)
		(fp_line
			(start 0.2 -0.77)
			(end 0.5 -0.77)
			(stroke
				(width 0.15)
				(type solid)
			)
			(layer "F.SilkS")
		)
		(fp_line
			(start 0.2 0.77)
			(end 0.5 0.77)
			(stroke
				(width 0.15)
				(type solid)
			)
			(layer "F.SilkS")
		)
		(fp_line
			(start 0.5 -0.47)
			(end 0.5 -0.77)
			(stroke
				(width 0.15)
				(type solid)
			)
			(layer "F.SilkS")
		)
		(fp_line
			(start 0.5 0.47)
			(end 0.5 0.77)
			(stroke
				(width 0.15)
				(type solid)
			)
			(layer "F.SilkS")
		)
		(fp_circle
			(center -0.77 -0.5)
			(end -0.724 -0.5)
			(stroke
				(width 0.15)
				(type solid)
			)
			(fill yes)
			(layer "F.SilkS")
		)
		(fp_rect
			(start -0.953 -1.201)
			(end 0.951 1.199)
			(stroke
				(width 0.05)
				(type solid)
			)
			(fill no)
			(layer "F.CrtYd")
		)
		(fp_line
			(start -0.454 0.698)
			(end -0.454 -0.701)
			(stroke
				(width 0.15)
				(type solid)
			)
			(layer "F.Fab")
		)
		(fp_line
			(start -0.25 -0.69)
			(end -0.45 -0.49)
			(stroke
				(width 0.15)
				(type solid)
			)
			(layer "F.Fab")
		)
		(fp_line
			(start 0.451 -0.701)
			(end -0.454 -0.701)
			(stroke
				(width 0.15)
				(type solid)
			)
			(layer "F.Fab")
		)
		(fp_line
			(start 0.451 0.698)
			(end -0.454 0.698)
			(stroke
				(width 0.15)
				(type solid)
			)
			(layer "F.Fab")
		)
		(fp_line
			(start 0.451 0.698)
			(end 0.451 -0.701)
			(stroke
				(width 0.15)
				(type solid)
			)
			(layer "F.Fab")
		)
		(pad "A1" smd circle
			(at -0.249 -0.499)
			(size 0.25 0.25)
			(layers "F.Cu" "F.Mask" "F.Paste")
			(net 25 "+1V35")
			(pinfunction "OUT")
			(pintype "power_out")
		)
		(pad "A2" smd circle
			(at 0.246 -0.499)
			(size 0.25 0.25)
			(layers "F.Cu" "F.Mask" "F.Paste")
			(net 740 "/DC-DC Converters/1V35_local")
			(pinfunction "IN")
			(pintype "power_in")
		)
		(pad "B1" smd circle
			(at -0.249 0.001)
			(size 0.25 0.25)
			(layers "F.Cu" "F.Mask" "F.Paste")
			(net 25 "+1V35")
			(pinfunction "OUT")
			(pintype "passive")
		)
		(pad "B2" smd circle
			(at 0.246 0.001)
			(size 0.25 0.25)
			(layers "F.Cu" "F.Mask" "F.Paste")
			(net 740 "/DC-DC Converters/1V35_local")
			(pinfunction "IN")
			(pintype "passive")
		)
		(pad "C1" smd circle
			(at -0.249 0.496)
			(size 0.25 0.25)
			(layers "F.Cu" "F.Mask" "F.Paste")
			(net 1 "GND")
			(pinfunction "GND")
			(pintype "power_in")
		)
		(pad "C2" smd circle
			(at 0.246 0.496)
			(size 0.25 0.25)
			(layers "F.Cu" "F.Mask" "F.Paste")
			(net 1053 "/DC-DC Converters/PB_CTRL.VDDR_EN")
			(pinfunction "EN")
			(pintype "input")
		)
	)
)
